(kicad_pcb
	(version 20260206)
	(generator "pcbnew")
	(generator_version "10.0")
	(general
		(thickness 1.6)
		(legacy_teardrops no)
	)
	(paper "A4")
	(title_block
		(title "04192023_DAF0TMB3IC0_F0TG_MB_C_brd_V02_OCP.brd")
		(comment 1 "Grand Teton / footprints 1582-1589 of 8354")
	)
	(layers
		(0 "F.Cu" signal "TOP")
		(4 "In1.Cu" signal "GND")
		(6 "In2.Cu" signal "IN1")
		(8 "In3.Cu" signal "GND1")
		(10 "In4.Cu" signal "IN2")
		(12 "In5.Cu" signal "GND2")
		(14 "In6.Cu" signal "IN3")
		(16 "In7.Cu" signal "GND3")
		(18 "In8.Cu" signal "VCC")
		(20 "In9.Cu" signal "VCC1")
		(22 "In10.Cu" signal "GND4")
		(24 "In11.Cu" signal "IN4")
		(26 "In12.Cu" signal "GND5")
		(28 "In13.Cu" signal "IN5")
		(30 "In14.Cu" signal "GND6")
		(32 "In15.Cu" signal "IN6")
		(34 "In16.Cu" signal "GND7")
		(2 "B.Cu" signal "BOTTOM")
		(9 "F.Adhes" user "F.Adhesive")
		(11 "B.Adhes" user "B.Adhesive")
		(13 "F.Paste" user "Package Geometry/Pastemask Top")
		(15 "B.Paste" user "Package Geometry/Pastemask Bottom")
		(5 "F.SilkS" user "Ref Des/Silkscreen Top")
		(7 "B.SilkS" user "Ref Des/Silkscreen Bottom")
		(1 "F.Mask" user "Board Geometry/Soldermask Top")
		(3 "B.Mask" user "Board Geometry/Soldermask Bottom")
		(17 "Dwgs.User" user "User.Drawings")
		(19 "Cmts.User" user "User.Comments")
		(21 "Eco1.User" user "User.Eco1")
		(23 "Eco2.User" user "User.Eco2")
		(25 "Edge.Cuts" user "Board Geometry/Outline")
		(27 "Margin" user)
		(31 "F.CrtYd" user "Package Geometry/Place Bound Top")
		(29 "B.CrtYd" user "Package Geometry/Place Bound Bottom")
		(35 "F.Fab" user "Ref Des/Assembly Top")
		(33 "B.Fab" user "Ref Des/Assembly Bottom")
	)
	(footprint ""
		(layer "F.Cu")
		(at 177.544984 -147.086574 90)
		(property "Reference" "R590"
			(at 0 0 90)
			(layer "F.SilkS")
			(hide yes)
			(effects
				(font
					(size 1.27 1.27)
				)
			)
		)
		(property "Value" ""
			(at 0 0 90)
			(layer "F.Fab")
			(effects
				(font
					(size 1.27 1.27)
				)
			)
		)
		(duplicate_pad_numbers_are_jumpers no)
		(fp_line
			(start 0.7874 -0.4064)
			(end 0.7874 0.4064)
			(stroke
				(width 0.1524)
				(type default)
			)
			(layer "F.SilkS")
		)
		(fp_line
			(start -0.7874 -0.4064)
			(end 0.7874 -0.4064)
			(stroke
				(width 0.1524)
				(type default)
			)
			(layer "F.SilkS")
		)
		(fp_line
			(start 0.7874 0.4064)
			(end -0.7874 0.4064)
			(stroke
				(width 0.1524)
				(type default)
			)
			(layer "F.SilkS")
		)
		(fp_line
			(start -0.7874 0.4064)
			(end -0.7874 -0.4064)
			(stroke
				(width 0.1524)
				(type default)
			)
			(layer "F.SilkS")
		)
		(fp_line
			(start -0.12065 -0.305054)
			(end -0.12065 -0.2794)
			(stroke
				(width 0.1)
				(type default)
			)
			(layer "F.Fab")
		)
		(fp_line
			(start -0.67945 -0.305054)
			(end -0.12065 -0.305054)
			(stroke
				(width 0.1)
				(type default)
			)
			(layer "F.Fab")
		)
		(fp_line
			(start 0.67945 -0.3048)
			(end 0.67945 0.3048)
			(stroke
				(width 0.1)
				(type default)
			)
			(layer "F.Fab")
		)
		(fp_line
			(start 0.12065 -0.3048)
			(end 0.67945 -0.3048)
			(stroke
				(width 0.1)
				(type default)
			)
			(layer "F.Fab")
		)
		(fp_line
			(start 0.12065 -0.2794)
			(end 0.12065 -0.3048)
			(stroke
				(width 0.1)
				(type default)
			)
			(layer "F.Fab")
		)
		(fp_line
			(start -0.12065 -0.2794)
			(end 0.12065 -0.2794)
			(stroke
				(width 0.1)
				(type default)
			)
			(layer "F.Fab")
		)
		(fp_line
			(start 0.120396 0.2794)
			(end -0.12065 0.2794)
			(stroke
				(width 0.1)
				(type default)
			)
			(layer "F.Fab")
		)
		(fp_line
			(start -0.12065 0.2794)
			(end -0.12065 0.3048)
			(stroke
				(width 0.1)
				(type default)
			)
			(layer "F.Fab")
		)
		(fp_line
			(start 0.67945 0.3048)
			(end 0.120396 0.3048)
			(stroke
				(width 0.1)
				(type default)
			)
			(layer "F.Fab")
		)
		(fp_line
			(start 0.120396 0.3048)
			(end 0.120396 0.2794)
			(stroke
				(width 0.1)
				(type default)
			)
			(layer "F.Fab")
		)
		(fp_line
			(start -0.12065 0.3048)
			(end -0.67945 0.3048)
			(stroke
				(width 0.1)
				(type default)
			)
			(layer "F.Fab")
		)
		(fp_line
			(start -0.67945 0.3048)
			(end -0.67945 -0.305054)
			(stroke
				(width 0.1)
				(type default)
			)
			(layer "F.Fab")
		)
		(pad "1" smd circle
			(at -0.40005 0 90)
			(size 0 0)
			(layers "F.Cu" "F.Mask" "F.Paste")
			(net "P3V3_AUX")
		)
		(pad "2" smd circle
			(at 0.40005 0 90)
			(size 0 0)
			(layers "F.Cu" "F.Mask" "F.Paste")
			(net "SMB_CPU0_4_XLTR_SDA")
		)
	)
	(footprint ""
		(layer "F.Cu")
		(at 40.116506 19.444716 -90)
		(property "Reference" "U25_BP"
			(at 0 0 270)
			(layer "F.SilkS")
			(hide yes)
			(effects
				(font
					(size 1.27 1.27)
				)
			)
		)
		(property "Value" ""
			(at 0 0 270)
			(layer "F.Fab")
			(effects
				(font
					(size 1.27 1.27)
				)
			)
		)
		(duplicate_pad_numbers_are_jumpers no)
		(pad "1" smd circle
			(at 0 0 270)
			(size 0.762 0.762)
			(layers "F.Cu" "F.Mask" "F.Paste")
			(net "Net_10789")
		)
	)
	(footprint ""
		(layer "F.Cu")
		(at 184.3405 -397.848582 180)
		(property "Reference" "R2586"
			(at 0 0 180)
			(layer "F.SilkS")
			(hide yes)
			(effects
				(font
					(size 1.27 1.27)
				)
			)
		)
		(property "Value" ""
			(at 0 0 180)
			(layer "F.Fab")
			(effects
				(font
					(size 1.27 1.27)
				)
			)
		)
		(duplicate_pad_numbers_are_jumpers no)
		(fp_line
			(start 0.7874 0.4064)
			(end -0.7874 0.4064)
			(stroke
				(width 0.1524)
				(type default)
			)
			(layer "F.SilkS")
		)
		(fp_line
			(start 0.7874 -0.4064)
			(end 0.7874 0.4064)
			(stroke
				(width 0.1524)
				(type default)
			)
			(layer "F.SilkS")
		)
		(fp_line
			(start -0.7874 0.4064)
			(end -0.7874 -0.4064)
			(stroke
				(width 0.1524)
				(type default)
			)
			(layer "F.SilkS")
		)
		(fp_line
			(start -0.7874 -0.4064)
			(end 0.7874 -0.4064)
			(stroke
				(width 0.1524)
				(type default)
			)
			(layer "F.SilkS")
		)
		(fp_line
			(start 0.67945 0.3048)
			(end 0.120396 0.3048)
			(stroke
				(width 0.1)
				(type default)
			)
			(layer "F.Fab")
		)
		(fp_line
			(start 0.67945 -0.3048)
			(end 0.67945 0.3048)
			(stroke
				(width 0.1)
				(type default)
			)
			(layer "F.Fab")
		)
		(fp_line
			(start 0.12065 -0.2794)
			(end 0.12065 -0.3048)
			(stroke
				(width 0.1)
				(type default)
			)
			(layer "F.Fab")
		)
		(fp_line
			(start 0.12065 -0.3048)
			(end 0.67945 -0.3048)
			(stroke
				(width 0.1)
				(type default)
			)
			(layer "F.Fab")
		)
		(fp_line
			(start 0.120396 0.3048)
			(end 0.120396 0.2794)
			(stroke
				(width 0.1)
				(type default)
			)
			(layer "F.Fab")
		)
		(fp_line
			(start 0.120396 0.2794)
			(end -0.12065 0.2794)
			(stroke
				(width 0.1)
				(type default)
			)
			(layer "F.Fab")
		)
		(fp_line
			(start -0.12065 0.3048)
			(end -0.67945 0.3048)
			(stroke
				(width 0.1)
				(type default)
			)
			(layer "F.Fab")
		)
		(fp_line
			(start -0.12065 0.2794)
			(end -0.12065 0.3048)
			(stroke
				(width 0.1)
				(type default)
			)
			(layer "F.Fab")
		)
		(fp_line
			(start -0.12065 -0.2794)
			(end 0.12065 -0.2794)
			(stroke
				(width 0.1)
				(type default)
			)
			(layer "F.Fab")
		)
		(fp_line
			(start -0.12065 -0.305054)
			(end -0.12065 -0.2794)
			(stroke
				(width 0.1)
				(type default)
			)
			(layer "F.Fab")
		)
		(fp_line
			(start -0.67945 0.3048)
			(end -0.67945 -0.305054)
			(stroke
				(width 0.1)
				(type default)
			)
			(layer "F.Fab")
		)
		(fp_line
			(start -0.67945 -0.305054)
			(end -0.12065 -0.305054)
			(stroke
				(width 0.1)
				(type default)
			)
			(layer "F.Fab")
		)
		(pad "1" smd circle
			(at -0.40005 0 180)
			(size 0 0)
			(layers "F.Cu" "F.Mask" "F.Paste")
			(net "HSC_EN")
		)
		(pad "2" smd circle
			(at 0.40005 0 180)
			(size 0 0)
			(layers "F.Cu" "F.Mask" "F.Paste")
			(net "HSC_EN_R")
		)
	)
	(footprint ""
		(layer "F.Cu")
		(at 435.997858 -107.78236 180)
		(property "Reference" "PC5328"
			(at 0 0 180)
			(layer "F.SilkS")
			(hide yes)
			(effects
				(font
					(size 1.27 1.27)
				)
			)
		)
		(property "Value" ""
			(at 0 0 180)
			(layer "F.Fab")
			(effects
				(font
					(size 1.27 1.27)
				)
			)
		)
		(duplicate_pad_numbers_are_jumpers no)
		(fp_line
			(start 0.7874 0.4064)
			(end -0.7874 0.4064)
			(stroke
				(width 0.1524)
				(type default)
			)
			(layer "F.SilkS")
		)
		(fp_line
			(start 0.7874 -0.4064)
			(end 0.7874 0.4064)
			(stroke
				(width 0.1524)
				(type default)
			)
			(layer "F.SilkS")
		)
		(fp_line
			(start -0.7874 0.4064)
			(end -0.7874 -0.4064)
			(stroke
				(width 0.1524)
				(type default)
			)
			(layer "F.SilkS")
		)
		(fp_line
			(start -0.7874 -0.4064)
			(end 0.7874 -0.4064)
			(stroke
				(width 0.1524)
				(type default)
			)
			(layer "F.SilkS")
		)
		(fp_line
			(start 0.67945 0.3048)
			(end 0.120396 0.3048)
			(stroke
				(width 0.1)
				(type default)
			)
			(layer "F.Fab")
		)
		(fp_line
			(start 0.67945 -0.3048)
			(end 0.67945 0.3048)
			(stroke
				(width 0.1)
				(type default)
			)
			(layer "F.Fab")
		)
		(fp_line
			(start 0.12065 -0.2794)
			(end 0.12065 -0.3048)
			(stroke
				(width 0.1)
				(type default)
			)
			(layer "F.Fab")
		)
		(fp_line
			(start 0.12065 -0.3048)
			(end 0.67945 -0.3048)
			(stroke
				(width 0.1)
				(type default)
			)
			(layer "F.Fab")
		)
		(fp_line
			(start 0.120396 0.3048)
			(end 0.120396 0.2794)
			(stroke
				(width 0.1)
				(type default)
			)
			(layer "F.Fab")
		)
		(fp_line
			(start 0.120396 0.2794)
			(end -0.12065 0.2794)
			(stroke
				(width 0.1)
				(type default)
			)
			(layer "F.Fab")
		)
		(fp_line
			(start -0.12065 0.3048)
			(end -0.67945 0.3048)
			(stroke
				(width 0.1)
				(type default)
			)
			(layer "F.Fab")
		)
		(fp_line
			(start -0.12065 0.2794)
			(end -0.12065 0.3048)
			(stroke
				(width 0.1)
				(type default)
			)
			(layer "F.Fab")
		)
		(fp_line
			(start -0.12065 -0.2794)
			(end 0.12065 -0.2794)
			(stroke
				(width 0.1)
				(type default)
			)
			(layer "F.Fab")
		)
		(fp_line
			(start -0.12065 -0.305054)
			(end -0.12065 -0.2794)
			(stroke
				(width 0.1)
				(type default)
			)
			(layer "F.Fab")
		)
		(fp_line
			(start -0.67945 0.3048)
			(end -0.67945 -0.305054)
			(stroke
				(width 0.1)
				(type default)
			)
			(layer "F.Fab")
		)
		(fp_line
			(start -0.67945 -0.305054)
			(end -0.12065 -0.305054)
			(stroke
				(width 0.1)
				(type default)
			)
			(layer "F.Fab")
		)
		(pad "1" smd circle
			(at -0.40005 0 180)
			(size 0 0)
			(layers "F.Cu" "F.Mask" "F.Paste")
			(net "P3V3_AUX")
		)
		(pad "2" smd circle
			(at 0.40005 0 180)
			(size 0 0)
			(layers "F.Cu" "F.Mask" "F.Paste")
			(net "GND")
		)
	)
	(footprint ""
		(layer "F.Cu")
		(at 6.870192 -389.439912)
		(property "Reference" "H3"
			(at -2.5146 -3.58013 0)
			(unlocked yes)
			(layer "F.SilkS")
			(effects
				(font
					(size 0.7874 0.5842)
					(thickness 0.1524)
				)
				(justify left)
			)
		)
		(property "Value" ""
			(at 0 0 0)
			(layer "F.Fab")
			(effects
				(font
					(size 1.27 1.27)
				)
			)
		)
		(duplicate_pad_numbers_are_jumpers no)
		(pad "1" thru_hole circle
			(at 0 0)
			(size 6.1976 6.1976)
			(drill 3.7338)
			(layers "*.Cu" "*.Mask")
			(remove_unused_layers no)
			(net "GND")
			(clearance -0.9779)
			(padstack
				(mode front_inner_back)
				(layer "Inner"
					(shape circle)
					(size 5.5372 5.5372)
					(clearance -0.6477)
				)
				(layer "B.Cu"
					(shape circle)
					(size 6.1976 6.1976)
					(clearance -0.9779)
				)
			)
		)
	)
	(footprint ""
		(layer "F.Cu")
		(at 322.837048 -41.160954 180)
		(property "Reference" "R3682"
			(at 0 0 180)
			(layer "F.SilkS")
			(hide yes)
			(effects
				(font
					(size 1.27 1.27)
				)
			)
		)
		(property "Value" ""
			(at 0 0 180)
			(layer "F.Fab")
			(effects
				(font
					(size 1.27 1.27)
				)
			)
		)
		(duplicate_pad_numbers_are_jumpers no)
		(fp_line
			(start 0.7874 0.4064)
			(end -0.7874 0.4064)
			(stroke
				(width 0.1524)
				(type default)
			)
			(layer "F.SilkS")
		)
		(fp_line
			(start 0.7874 -0.4064)
			(end 0.7874 0.4064)
			(stroke
				(width 0.1524)
				(type default)
			)
			(layer "F.SilkS")
		)
		(fp_line
			(start -0.7874 0.4064)
			(end -0.7874 -0.4064)
			(stroke
				(width 0.1524)
				(type default)
			)
			(layer "F.SilkS")
		)
		(fp_line
			(start -0.7874 -0.4064)
			(end 0.7874 -0.4064)
			(stroke
				(width 0.1524)
				(type default)
			)
			(layer "F.SilkS")
		)
		(fp_line
			(start 0.67945 0.3048)
			(end 0.120396 0.3048)
			(stroke
				(width 0.1)
				(type default)
			)
			(layer "F.Fab")
		)
		(fp_line
			(start 0.67945 -0.3048)
			(end 0.67945 0.3048)
			(stroke
				(width 0.1)
				(type default)
			)
			(layer "F.Fab")
		)
		(fp_line
			(start 0.12065 -0.2794)
			(end 0.12065 -0.3048)
			(stroke
				(width 0.1)
				(type default)
			)
			(layer "F.Fab")
		)
		(fp_line
			(start 0.12065 -0.3048)
			(end 0.67945 -0.3048)
			(stroke
				(width 0.1)
				(type default)
			)
			(layer "F.Fab")
		)
		(fp_line
			(start 0.120396 0.3048)
			(end 0.120396 0.2794)
			(stroke
				(width 0.1)
				(type default)
			)
			(layer "F.Fab")
		)
		(fp_line
			(start 0.120396 0.2794)
			(end -0.12065 0.2794)
			(stroke
				(width 0.1)
				(type default)
			)
			(layer "F.Fab")
		)
		(fp_line
			(start -0.12065 0.3048)
			(end -0.67945 0.3048)
			(stroke
				(width 0.1)
				(type default)
			)
			(layer "F.Fab")
		)
		(fp_line
			(start -0.12065 0.2794)
			(end -0.12065 0.3048)
			(stroke
				(width 0.1)
				(type default)
			)
			(layer "F.Fab")
		)
		(fp_line
			(start -0.12065 -0.2794)
			(end 0.12065 -0.2794)
			(stroke
				(width 0.1)
				(type default)
			)
			(layer "F.Fab")
		)
		(fp_line
			(start -0.12065 -0.305054)
			(end -0.12065 -0.2794)
			(stroke
				(width 0.1)
				(type default)
			)
			(layer "F.Fab")
		)
		(fp_line
			(start -0.67945 0.3048)
			(end -0.67945 -0.305054)
			(stroke
				(width 0.1)
				(type default)
			)
			(layer "F.Fab")
		)
		(fp_line
			(start -0.67945 -0.305054)
			(end -0.12065 -0.305054)
			(stroke
				(width 0.1)
				(type default)
			)
			(layer "F.Fab")
		)
		(pad "1" smd rect
			(at -0.40005 0)
			(size 0.4572 0.508)
			(layers "F.Cu" "F.Mask" "F.Paste")
			(net "P3V3_AUX_ADC")
		)
		(pad "2" smd rect
			(at 0.40005 0)
			(size 0.4572 0.508)
			(layers "F.Cu" "F.Mask" "F.Paste")
			(net "P3V3_AUX_ADC_TIC")
		)
	)
	(footprint ""
		(layer "F.Cu")
		(at 302.15078 -351.368106 -90)
		(property "Reference" "PC155"
			(at 0 0 270)
			(layer "F.SilkS")
			(hide yes)
			(effects
				(font
					(size 1.27 1.27)
				)
			)
		)
		(property "Value" ""
			(at 0 0 270)
			(layer "F.Fab")
			(effects
				(font
					(size 1.27 1.27)
				)
			)
		)
		(duplicate_pad_numbers_are_jumpers no)
		(fp_line
			(start -0.7874 0.4064)
			(end -0.7874 -0.4064)
			(stroke
				(width 0.1524)
				(type default)
			)
			(layer "F.SilkS")
		)
		(fp_line
			(start 0.7874 0.4064)
			(end -0.7874 0.4064)
			(stroke
				(width 0.1524)
				(type default)
			)
			(layer "F.SilkS")
		)
		(fp_line
			(start -0.7874 -0.4064)
			(end 0.7874 -0.4064)
			(stroke
				(width 0.1524)
				(type default)
			)
			(layer "F.SilkS")
		)
		(fp_line
			(start 0.7874 -0.4064)
			(end 0.7874 0.4064)
			(stroke
				(width 0.1524)
				(type default)
			)
			(layer "F.SilkS")
		)
		(fp_line
			(start -0.67945 0.3048)
			(end -0.67945 -0.305054)
			(stroke
				(width 0.1)
				(type default)
			)
			(layer "F.Fab")
		)
		(fp_line
			(start -0.12065 0.3048)
			(end -0.67945 0.3048)
			(stroke
				(width 0.1)
				(type default)
			)
			(layer "F.Fab")
		)
		(fp_line
			(start 0.120396 0.3048)
			(end 0.120396 0.2794)
			(stroke
				(width 0.1)
				(type default)
			)
			(layer "F.Fab")
		)
		(fp_line
			(start 0.67945 0.3048)
			(end 0.120396 0.3048)
			(stroke
				(width 0.1)
				(type default)
			)
			(layer "F.Fab")
		)
		(fp_line
			(start -0.12065 0.2794)
			(end -0.12065 0.3048)
			(stroke
				(width 0.1)
				(type default)
			)
			(layer "F.Fab")
		)
		(fp_line
			(start 0.120396 0.2794)
			(end -0.12065 0.2794)
			(stroke
				(width 0.1)
				(type default)
			)
			(layer "F.Fab")
		)
		(fp_line
			(start -0.12065 -0.2794)
			(end 0.12065 -0.2794)
			(stroke
				(width 0.1)
				(type default)
			)
			(layer "F.Fab")
		)
		(fp_line
			(start 0.12065 -0.2794)
			(end 0.12065 -0.3048)
			(stroke
				(width 0.1)
				(type default)
			)
			(layer "F.Fab")
		)
		(fp_line
			(start 0.12065 -0.3048)
			(end 0.67945 -0.3048)
			(stroke
				(width 0.1)
				(type default)
			)
			(layer "F.Fab")
		)
		(fp_line
			(start 0.67945 -0.3048)
			(end 0.67945 0.3048)
			(stroke
				(width 0.1)
				(type default)
			)
			(layer "F.Fab")
		)
		(fp_line
			(start -0.67945 -0.305054)
			(end -0.12065 -0.305054)
			(stroke
				(width 0.1)
				(type default)
			)
			(layer "F.Fab")
		)
		(fp_line
			(start -0.12065 -0.305054)
			(end -0.12065 -0.2794)
			(stroke
				(width 0.1)
				(type default)
			)
			(layer "F.Fab")
		)
		(pad "1" smd circle
			(at -0.40005 0 270)
			(size 0 0)
			(layers "F.Cu" "F.Mask" "F.Paste")
			(net "SW_PVDDIO_P0_BOOT1_R")
		)
		(pad "2" smd circle
			(at 0.40005 0 270)
			(size 0 0)
			(layers "F.Cu" "F.Mask" "F.Paste")
			(net "SW_PVDDIO_P0_BOOTR1")
		)
	)
	(footprint ""
		(layer "F.Cu")
		(at 296.29989 -358.769666 180)
		(property "Reference" "PC164"
			(at 1.78689 5.439664 0)
			(unlocked yes)
			(layer "F.SilkS")
			(effects
				(font
					(size 0.7874 0.5842)
					(thickness 0.1524)
				)
				(justify left)
			)
		)
		(property "Value" ""
			(at 0 0 180)
			(layer "F.Fab")
			(effects
				(font
					(size 1.27 1.27)
				)
			)
		)
		(duplicate_pad_numbers_are_jumpers no)
		(fp_line
			(start -3.400044 1.249934)
			(end 3.400044 1.249934)
			(stroke
				(width 0.1524)
				(type default)
			)
			(layer "F.SilkS")
		)
		(fp_circle
			(center 0 1.249934)
			(end -3.400044 1.249934)
			(stroke
				(width 0.1524)
				(type default)
			)
			(fill no)
			(layer "F.SilkS")
		)
		(fp_poly
			(pts
				(arc
					(start 3.400044 1.249934)
					(mid 0 4.649978)
					(end -3.400044 1.249934)
				)
			)
			(stroke
				(width 0)
				(type default)
			)
			(fill yes)
			(layer "F.SilkS")
		)
		(fp_circle
			(center 0 1.249934)
			(end -3.400044 1.249934)
			(stroke
				(width 0.1)
				(type default)
			)
			(fill no)
			(layer "F.Fab")
		)
		(pad "1" thru_hole rect
			(at 0 0 180)
			(size 1.524 1.524)
			(drill 1.016)
			(layers "*.Cu" "*.Mask")
			(remove_unused_layers no)
			(net "SW_P12V_AUX_PVDDIO_P0_FLT")
			(clearance 0)
			(padstack
				(mode front_inner_back)
				(layer "Inner"
					(shape circle)
					(size 1.524 1.524)
					(clearance 0)
				)
				(layer "B.Cu"
					(shape rect)
					(size 1.524 1.524)
					(clearance 0)
				)
			)
		)
		(pad "2" thru_hole circle
			(at 0 2.500122 180)
			(size 1.524 1.524)
			(drill 1.016)
			(layers "*.Cu" "*.Mask")
			(remove_unused_layers no)
			(net "GND")
			(clearance 0)
		)
	)
)
